(kicad_pcb
	(version 20260206)
	(generator "pcbnew")
	(generator_version "10.0")
	(general
		(thickness 1.6)
		(legacy_teardrops no)
	)
	(paper "A4")
	(title_block
		(title "baseboard — 13948-1b.1110WZS1818.brd")
		(comment 1 "Honey Badger (Wiwynn) / footprints 1626-1632 of 2523")
	)
	(layers
		(0 "F.Cu" signal "TOP")
		(4 "In1.Cu" signal "L2GND")
		(6 "In2.Cu" signal "L3")
		(8 "In3.Cu" signal "L4VCC")
		(10 "In4.Cu" signal "L5VCC")
		(12 "In5.Cu" signal "L6")
		(14 "In6.Cu" signal "L7GND")
		(2 "B.Cu" signal "BOTTOM")
		(9 "F.Adhes" user "F.Adhesive")
		(11 "B.Adhes" user "B.Adhesive")
		(13 "F.Paste" user "Package Geometry/Pastemask Top")
		(15 "B.Paste" user "Package Geometry/Pastemask Bottom")
		(5 "F.SilkS" user "Ref Des/Silkscreen Top")
		(7 "B.SilkS" user "Ref Des/Silkscreen Bottom")
		(1 "F.Mask" user "Board Geometry/Soldermask Top")
		(3 "B.Mask" user "Board Geometry/Soldermask Bottom")
		(17 "Dwgs.User" user "User.Drawings")
		(19 "Cmts.User" user "User.Comments")
		(21 "Eco1.User" user "User.Eco1")
		(23 "Eco2.User" user "User.Eco2")
		(25 "Edge.Cuts" user "Board Geometry/Outline")
		(27 "Margin" user)
		(31 "F.CrtYd" user "Package Geometry/Place Bound Top")
		(29 "B.CrtYd" user "Package Geometry/Place Bound Bottom")
		(35 "F.Fab" user "Ref Des/Assembly Top")
		(33 "B.Fab" user "Ref Des/Assembly Bottom")
	)
	(footprint ""
		(layer "F.Cu")
		(at 86.49716 -43.561 -90)
		(property "Reference" "SC891"
			(at 0 0 270)
			(layer "F.SilkS")
			(hide yes)
			(effects
				(font
					(size 1.27 1.27)
				)
			)
		)
		(property "Value" "SCD01U10V1KX-GP"
			(at -2.8321 -1.7399 270)
			(unlocked yes)
			(layer "F.Fab")
			(hide yes)
			(effects
				(font
					(size 1.016 1.016)
					(thickness 0.1524)
				)
			)
		)
		(property "Device Type" "C0201H13"
			(at -2.8321 -3.2639 270)
			(unlocked yes)
			(layer "F.Fab")
			(hide yes)
			(effects
				(font
					(size 1.016 1.016)
					(thickness 0.1524)
				)
			)
		)
		(duplicate_pad_numbers_are_jumpers no)
		(fp_rect
			(start -0.2794 0.6477)
			(end 0.2794 -0.6477)
			(stroke
				(width 0)
				(type default)
			)
			(fill no)
			(layer "F.CrtYd")
		)
		(fp_rect
			(start -0.2794 0.6477)
			(end 0.2794 -0.6477)
			(stroke
				(width 0)
				(type default)
			)
			(fill no)
			(layer "F.Fab")
		)
		(pad "1" smd custom
			(at 0 -0.2794 270)
			(size 0.0762 0.0762)
			(layers "F.Cu" "F.Mask" "F.Paste")
			(net "SAS3008_RAID_TX_C_P5")
			(options
				(clearance outline)
				(anchor circle)
			)
			(primitives
				(gr_poly
					(pts
						(arc
							(start 0.1524 -0.127)
							(mid 0.137521 -0.162921)
							(end 0.1016 -0.1778)
						)
						(arc
							(start -0.1016 -0.1778)
							(mid -0.137521 -0.162921)
							(end -0.1524 -0.127)
						)
						(arc
							(start -0.1524 0.127)
							(mid -0.137521 0.162921)
							(end -0.1016 0.1778)
						)
						(arc
							(start 0.1016 0.1778)
							(mid 0.137521 0.162921)
							(end 0.1524 0.127)
						)
					)
					(width 0)
					(fill yes)
				)
			)
		)
		(pad "2" smd custom
			(at 0 0.2794 270)
			(size 0.0762 0.0762)
			(layers "F.Cu" "F.Mask" "F.Paste")
			(net "IOC_RAID_TX_P5")
			(options
				(clearance outline)
				(anchor circle)
			)
			(primitives
				(gr_poly
					(pts
						(arc
							(start 0.1524 -0.127)
							(mid 0.137521 -0.162921)
							(end 0.1016 -0.1778)
						)
						(arc
							(start -0.1016 -0.1778)
							(mid -0.137521 -0.162921)
							(end -0.1524 -0.127)
						)
						(arc
							(start -0.1524 0.127)
							(mid -0.137521 0.162921)
							(end -0.1016 0.1778)
						)
						(arc
							(start 0.1016 0.1778)
							(mid 0.137521 0.162921)
							(end 0.1524 0.127)
						)
					)
					(width 0)
					(fill yes)
				)
			)
		)
	)
	(footprint ""
		(layer "F.Cu")
		(at 85.730842 -122.118882 -90)
		(property "Reference" "SU65"
			(at 0 0 270)
			(layer "F.SilkS")
			(hide yes)
			(effects
				(font
					(size 1.27 1.27)
				)
			)
		)
		(property "Value" "PCA9306DCTT-GP"
			(at 0 -11.6332 270)
			(unlocked yes)
			(layer "F.Fab")
			(hide yes)
			(effects
				(font
					(size 1.016 1.016)
					(thickness 0.1524)
				)
			)
		)
		(property "Device Type" "SSOIC8H52"
			(at 0 -13.1572 270)
			(unlocked yes)
			(layer "F.Fab")
			(hide yes)
			(effects
				(font
					(size 1.016 1.016)
					(thickness 0.1524)
				)
			)
		)
		(duplicate_pad_numbers_are_jumpers no)
		(fp_line
			(start -1.524 0.5842)
			(end -1.524 2.286)
			(stroke
				(width 0.508)
				(type default)
			)
			(layer "F.SilkS")
		)
		(fp_line
			(start 1.0668 0.5842)
			(end -1.524 0.5842)
			(stroke
				(width 0.1524)
				(type default)
			)
			(layer "F.SilkS")
		)
		(fp_line
			(start -1.397 0)
			(end -1.7018 0.3048)
			(stroke
				(width 0.1524)
				(type default)
			)
			(layer "F.SilkS")
		)
		(fp_line
			(start -1.397 0)
			(end -1.7018 -0.3048)
			(stroke
				(width 0.1524)
				(type default)
			)
			(layer "F.SilkS")
		)
		(fp_line
			(start -1.7018 -0.5842)
			(end -1.7018 2.286)
			(stroke
				(width 0.1524)
				(type default)
			)
			(layer "F.SilkS")
		)
		(fp_line
			(start -1.7018 -0.5842)
			(end 1.0668 -0.5842)
			(stroke
				(width 0.1524)
				(type default)
			)
			(layer "F.SilkS")
		)
		(fp_line
			(start 1.0668 -0.5842)
			(end 1.0668 0.5842)
			(stroke
				(width 0.1524)
				(type default)
			)
			(layer "F.SilkS")
		)
		(fp_poly
			(pts
				(xy -1.1684 -0.5842) (xy 1.0668 -0.5842) (xy 1.0668 0.5842) (xy -1.1684 0.5842)
			)
			(stroke
				(width 0)
				(type default)
			)
			(fill yes)
			(layer "F.SilkS")
		)
		(fp_poly
			(pts
				(xy -1.778 2.54) (xy 1.778 2.54) (xy 1.778 -2.54) (xy -1.778 -2.54)
			)
			(stroke
				(width 0)
				(type default)
			)
			(fill no)
			(layer "F.CrtYd")
		)
		(fp_poly
			(pts
				(xy -1.778 -2.54) (xy 1.778 -2.54) (xy 1.778 2.54) (xy -1.778 2.54)
			)
			(stroke
				(width 0)
				(type default)
			)
			(fill no)
			(layer "F.Fab")
		)
		(pad "1" smd rect
			(at -0.97536 1.6256 270)
			(size 0.3556 1.524)
			(layers "F.Cu" "F.Mask" "F.Paste")
			(net "GND")
		)
		(pad "2" smd rect
			(at -0.32512 1.6256 270)
			(size 0.3556 1.524)
			(layers "F.Cu" "F.Mask" "F.Paste")
			(net "P1V8_E")
		)
		(pad "3" smd rect
			(at 0.32512 1.6256 270)
			(size 0.3556 1.524)
			(layers "F.Cu" "F.Mask" "F.Paste")
			(net "EXP_I2C_SCL_1")
		)
		(pad "4" smd rect
			(at 0.97536 1.6256 270)
			(size 0.3556 1.524)
			(layers "F.Cu" "F.Mask" "F.Paste")
			(net "EXP_I2C_SDA_1")
		)
		(pad "5" smd rect
			(at 0.97536 -1.6256 270)
			(size 0.3556 1.524)
			(layers "F.Cu" "F.Mask" "F.Paste")
			(net "BMC_I2C_F_SDA")
		)
		(pad "6" smd rect
			(at 0.32512 -1.6256 270)
			(size 0.3556 1.524)
			(layers "F.Cu" "F.Mask" "F.Paste")
			(net "BMC_I2C_F_SCL")
		)
		(pad "7" smd rect
			(at -0.32512 -1.6256 270)
			(size 0.3556 1.524)
			(layers "F.Cu" "F.Mask" "F.Paste")
			(net "EXP_I2C_VREF_0")
		)
		(pad "8" smd rect
			(at -0.97536 -1.6256 270)
			(size 0.3556 1.524)
			(layers "F.Cu" "F.Mask" "F.Paste")
			(net "EXP_I2C_VREF_0")
		)
	)
	(footprint ""
		(layer "F.Cu")
		(at 199.39 -140.589 90)
		(property "Reference" "SR766"
			(at 0 0 90)
			(layer "F.SilkS")
			(hide yes)
			(effects
				(font
					(size 1.27 1.27)
				)
			)
		)
		(property "Value" "4K7R2F-GP"
			(at 0.064008 -3.993896 90)
			(unlocked yes)
			(layer "F.Fab")
			(hide yes)
			(effects
				(font
					(size 1.016 1.016)
					(thickness 0.1524)
				)
			)
		)
		(property "Device Type" "R402H16"
			(at 0.064008 -5.517896 90)
			(unlocked yes)
			(layer "F.Fab")
			(hide yes)
			(effects
				(font
					(size 1.016 1.016)
					(thickness 0.1524)
				)
			)
		)
		(duplicate_pad_numbers_are_jumpers no)
		(fp_line
			(start 0.508 -0.9398)
			(end -0.508 -0.9398)
			(stroke
				(width 0.1524)
				(type default)
			)
			(layer "F.SilkS")
		)
		(fp_line
			(start -0.508 -0.9398)
			(end -0.508 0.9398)
			(stroke
				(width 0.1524)
				(type default)
			)
			(layer "F.SilkS")
		)
		(fp_rect
			(start -0.508 0.9398)
			(end 0.508 -0.9398)
			(stroke
				(width 0)
				(type default)
			)
			(fill no)
			(layer "F.CrtYd")
		)
		(fp_rect
			(start -0.508 0.9398)
			(end 0.508 -0.9398)
			(stroke
				(width 0)
				(type default)
			)
			(fill no)
			(layer "F.Fab")
		)
		(pad "1" smd custom
			(at 0 -0.4445 90)
			(size 0.1397 0.1397)
			(layers "F.Cu" "F.Mask" "F.Paste")
			(net "EXP_EEPROM_A1")
			(options
				(clearance outline)
				(anchor circle)
			)
			(primitives
				(gr_poly
					(pts
						(arc
							(start -0.1778 -0.2794)
							(mid -0.249642 -0.249642)
							(end -0.2794 -0.1778)
						)
						(arc
							(start -0.2794 0.1778)
							(mid -0.249642 0.249642)
							(end -0.1778 0.2794)
						)
						(arc
							(start 0.1778 0.2794)
							(mid 0.249642 0.249642)
							(end 0.2794 0.1778)
						)
						(arc
							(start 0.2794 -0.1778)
							(mid 0.249642 -0.249642)
							(end 0.1778 -0.2794)
						)
					)
					(width 0)
					(fill yes)
				)
			)
		)
		(pad "2" smd custom
			(at 0 0.4445 90)
			(size 0.1397 0.1397)
			(layers "F.Cu" "F.Mask" "F.Paste")
			(net "GND")
			(options
				(clearance outline)
				(anchor circle)
			)
			(primitives
				(gr_poly
					(pts
						(arc
							(start -0.1778 -0.2794)
							(mid -0.249642 -0.249642)
							(end -0.2794 -0.1778)
						)
						(arc
							(start -0.2794 0.1778)
							(mid -0.249642 0.249642)
							(end -0.1778 0.2794)
						)
						(arc
							(start 0.1778 0.2794)
							(mid 0.249642 0.249642)
							(end 0.2794 0.1778)
						)
						(arc
							(start 0.2794 -0.1778)
							(mid 0.249642 -0.249642)
							(end 0.1778 -0.2794)
						)
					)
					(width 0)
					(fill yes)
				)
			)
		)
	)
	(footprint ""
		(layer "F.Cu")
		(at 301.752 -91.186 -90)
		(property "Reference" "R162"
			(at 0 0 270)
			(layer "F.SilkS")
			(hide yes)
			(effects
				(font
					(size 1.27 1.27)
				)
			)
		)
		(property "Value" "0R2J-2-GP"
			(at 0.064008 -3.993896 270)
			(unlocked yes)
			(layer "F.Fab")
			(hide yes)
			(effects
				(font
					(size 1.016 1.016)
					(thickness 0.1524)
				)
			)
		)
		(property "Device Type" "R402H16"
			(at 0.064008 -5.517896 270)
			(unlocked yes)
			(layer "F.Fab")
			(hide yes)
			(effects
				(font
					(size 1.016 1.016)
					(thickness 0.1524)
				)
			)
		)
		(duplicate_pad_numbers_are_jumpers no)
		(fp_line
			(start -0.508 -0.9398)
			(end -0.508 0.9398)
			(stroke
				(width 0.1524)
				(type default)
			)
			(layer "F.SilkS")
		)
		(fp_line
			(start 0.508 -0.9398)
			(end -0.508 -0.9398)
			(stroke
				(width 0.1524)
				(type default)
			)
			(layer "F.SilkS")
		)
		(fp_rect
			(start -0.508 0.9398)
			(end 0.508 -0.9398)
			(stroke
				(width 0)
				(type default)
			)
			(fill no)
			(layer "F.CrtYd")
		)
		(fp_rect
			(start -0.508 0.9398)
			(end 0.508 -0.9398)
			(stroke
				(width 0)
				(type default)
			)
			(fill no)
			(layer "F.Fab")
		)
		(pad "1" smd custom
			(at 0 -0.4445 270)
			(size 0.1397 0.1397)
			(layers "F.Cu" "F.Mask" "F.Paste")
			(net "BMC_I2C_D_SCL")
			(options
				(clearance outline)
				(anchor circle)
			)
			(primitives
				(gr_poly
					(pts
						(arc
							(start -0.1778 -0.2794)
							(mid -0.249642 -0.249642)
							(end -0.2794 -0.1778)
						)
						(arc
							(start -0.2794 0.1778)
							(mid -0.249642 0.249642)
							(end -0.1778 0.2794)
						)
						(arc
							(start 0.1778 0.2794)
							(mid 0.249642 0.249642)
							(end 0.2794 0.1778)
						)
						(arc
							(start 0.2794 -0.1778)
							(mid 0.249642 -0.249642)
							(end 0.1778 -0.2794)
						)
					)
					(width 0)
					(fill yes)
				)
			)
		)
		(pad "2" smd custom
			(at 0 0.4445 270)
			(size 0.1397 0.1397)
			(layers "F.Cu" "F.Mask" "F.Paste")
			(net "TEMP_2_SCL")
			(options
				(clearance outline)
				(anchor circle)
			)
			(primitives
				(gr_poly
					(pts
						(arc
							(start -0.1778 -0.2794)
							(mid -0.249642 -0.249642)
							(end -0.2794 -0.1778)
						)
						(arc
							(start -0.2794 0.1778)
							(mid -0.249642 0.249642)
							(end -0.1778 0.2794)
						)
						(arc
							(start 0.1778 0.2794)
							(mid 0.249642 0.249642)
							(end 0.2794 0.1778)
						)
						(arc
							(start 0.2794 -0.1778)
							(mid 0.249642 -0.249642)
							(end 0.1778 -0.2794)
						)
					)
					(width 0)
					(fill yes)
				)
			)
		)
	)
	(footprint ""
		(layer "F.Cu")
		(at 83.420966 -84.074 180)
		(property "Reference" "SC1154"
			(at 0 0 180)
			(layer "F.SilkS")
			(hide yes)
			(effects
				(font
					(size 1.27 1.27)
				)
			)
		)
		(property "Value" "SC22U6D3V5MX-2GP"
			(at -0.0762 -6.1214 180)
			(unlocked yes)
			(layer "F.Fab")
			(hide yes)
			(effects
				(font
					(size 1.016 1.016)
					(thickness 0.1524)
				)
			)
		)
		(property "Device Type" "C805H58"
			(at -0.0762 -8.1534 180)
			(unlocked yes)
			(layer "F.Fab")
			(hide yes)
			(effects
				(font
					(size 1.016 1.016)
					(thickness 0.1524)
				)
			)
		)
		(duplicate_pad_numbers_are_jumpers no)
		(fp_line
			(start 0.635 0)
			(end -0.635 0)
			(stroke
				(width 0.508)
				(type default)
			)
			(layer "F.SilkS")
		)
		(fp_rect
			(start -0.9652 1.778)
			(end 0.9652 -1.778)
			(stroke
				(width 0)
				(type default)
			)
			(fill no)
			(layer "F.CrtYd")
		)
		(fp_poly
			(pts
				(xy -0.9652 -1.778) (xy 0.9652 -1.778) (xy 0.9652 1.778) (xy -0.9652 1.778)
			)
			(stroke
				(width 0)
				(type default)
			)
			(fill no)
			(layer "F.Fab")
		)
		(pad "1" smd rect
			(at 0 -0.9652 180)
			(size 1.397 1.143)
			(layers "F.Cu" "F.Mask" "F.Paste")
			(net "PLLDDR_VDDA18")
		)
		(pad "2" smd rect
			(at 0 0.9652 180)
			(size 1.397 1.143)
			(layers "F.Cu" "F.Mask" "F.Paste")
			(net "GND")
		)
	)
	(footprint ""
		(layer "F.Cu")
		(at 86.24697 -112.014 180)
		(property "Reference" "SC1230"
			(at 0 0 180)
			(layer "F.SilkS")
			(hide yes)
			(effects
				(font
					(size 1.27 1.27)
				)
			)
		)
		(property "Value" "SCD1U6D3V1KX-GP"
			(at -2.8321 -1.7399 180)
			(unlocked yes)
			(layer "F.Fab")
			(hide yes)
			(effects
				(font
					(size 1.016 1.016)
					(thickness 0.1524)
				)
			)
		)
		(property "Device Type" "C0201H13"
			(at -2.8321 -3.2639 180)
			(unlocked yes)
			(layer "F.Fab")
			(hide yes)
			(effects
				(font
					(size 1.016 1.016)
					(thickness 0.1524)
				)
			)
		)
		(duplicate_pad_numbers_are_jumpers no)
		(fp_rect
			(start -0.2794 0.6477)
			(end 0.2794 -0.6477)
			(stroke
				(width 0)
				(type default)
			)
			(fill no)
			(layer "F.CrtYd")
		)
		(fp_rect
			(start -0.2794 0.6477)
			(end 0.2794 -0.6477)
			(stroke
				(width 0)
				(type default)
			)
			(fill no)
			(layer "F.Fab")
		)
		(pad "1" smd custom
			(at 0 -0.2794 180)
			(size 0.0762 0.0762)
			(layers "F.Cu" "F.Mask" "F.Paste")
			(net "P1V8_E")
			(options
				(clearance outline)
				(anchor circle)
			)
			(primitives
				(gr_poly
					(pts
						(arc
							(start 0.1524 -0.127)
							(mid 0.137521 -0.162921)
							(end 0.1016 -0.1778)
						)
						(arc
							(start -0.1016 -0.1778)
							(mid -0.137521 -0.162921)
							(end -0.1524 -0.127)
						)
						(arc
							(start -0.1524 0.127)
							(mid -0.137521 0.162921)
							(end -0.1016 0.1778)
						)
						(arc
							(start 0.1016 0.1778)
							(mid 0.137521 0.162921)
							(end 0.1524 0.127)
						)
					)
					(width 0)
					(fill yes)
				)
			)
		)
		(pad "2" smd custom
			(at 0 0.2794 180)
			(size 0.0762 0.0762)
			(layers "F.Cu" "F.Mask" "F.Paste")
			(net "GND")
			(options
				(clearance outline)
				(anchor circle)
			)
			(primitives
				(gr_poly
					(pts
						(arc
							(start 0.1524 -0.127)
							(mid 0.137521 -0.162921)
							(end 0.1016 -0.1778)
						)
						(arc
							(start -0.1016 -0.1778)
							(mid -0.137521 -0.162921)
							(end -0.1524 -0.127)
						)
						(arc
							(start -0.1524 0.127)
							(mid -0.137521 0.162921)
							(end -0.1016 0.1778)
						)
						(arc
							(start 0.1016 0.1778)
							(mid 0.137521 0.162921)
							(end 0.1524 0.127)
						)
					)
					(width 0)
					(fill yes)
				)
			)
		)
	)
	(footprint ""
		(layer "F.Cu")
		(at 319.913 -166.878 -90)
		(property "Reference" "R475"
			(at 0 0 270)
			(layer "F.SilkS")
			(hide yes)
			(effects
				(font
					(size 1.27 1.27)
				)
			)
		)
		(property "Value" "10KR2F-2-GP"
			(at 0.064008 -3.993896 270)
			(unlocked yes)
			(layer "F.Fab")
			(hide yes)
			(effects
				(font
					(size 1.016 1.016)
					(thickness 0.1524)
				)
			)
		)
		(property "Device Type" "R402H16"
			(at 0.064008 -5.517896 270)
			(unlocked yes)
			(layer "F.Fab")
			(hide yes)
			(effects
				(font
					(size 1.016 1.016)
					(thickness 0.1524)
				)
			)
		)
		(duplicate_pad_numbers_are_jumpers no)
		(fp_line
			(start -0.508 -0.9398)
			(end -0.508 0.9398)
			(stroke
				(width 0.1524)
				(type default)
			)
			(layer "F.SilkS")
		)
		(fp_line
			(start 0.508 -0.9398)
			(end -0.508 -0.9398)
			(stroke
				(width 0.1524)
				(type default)
			)
			(layer "F.SilkS")
		)
		(fp_rect
			(start -0.508 0.9398)
			(end 0.508 -0.9398)
			(stroke
				(width 0)
				(type default)
			)
			(fill no)
			(layer "F.CrtYd")
		)
		(fp_rect
			(start -0.508 0.9398)
			(end 0.508 -0.9398)
			(stroke
				(width 0)
				(type default)
			)
			(fill no)
			(layer "F.Fab")
		)
		(pad "1" smd custom
			(at 0 -0.4445 270)
			(size 0.1397 0.1397)
			(layers "F.Cu" "F.Mask" "F.Paste")
			(net "P3V3_STBY")
			(options
				(clearance outline)
				(anchor circle)
			)
			(primitives
				(gr_poly
					(pts
						(arc
							(start -0.1778 -0.2794)
							(mid -0.249642 -0.249642)
							(end -0.2794 -0.1778)
						)
						(arc
							(start -0.2794 0.1778)
							(mid -0.249642 0.249642)
							(end -0.1778 0.2794)
						)
						(arc
							(start 0.1778 0.2794)
							(mid 0.249642 0.249642)
							(end 0.2794 0.1778)
						)
						(arc
							(start 0.2794 -0.1778)
							(mid 0.249642 -0.249642)
							(end 0.1778 -0.2794)
						)
					)
					(width 0)
					(fill yes)
				)
			)
		)
		(pad "2" smd custom
			(at 0 0.4445 270)
			(size 0.1397 0.1397)
			(layers "F.Cu" "F.Mask" "F.Paste")
			(net "BMC_I2C_C_SDA")
			(options
				(clearance outline)
				(anchor circle)
			)
			(primitives
				(gr_poly
					(pts
						(arc
							(start -0.1778 -0.2794)
							(mid -0.249642 -0.249642)
							(end -0.2794 -0.1778)
						)
						(arc
							(start -0.2794 0.1778)
							(mid -0.249642 0.249642)
							(end -0.1778 0.2794)
						)
						(arc
							(start 0.1778 0.2794)
							(mid 0.249642 0.249642)
							(end 0.2794 0.1778)
						)
						(arc
							(start 0.2794 -0.1778)
							(mid 0.249642 -0.249642)
							(end 0.1778 -0.2794)
						)
					)
					(width 0)
					(fill yes)
				)
			)
		)
	)
)
